(kicad_pcb
	(version 20260206)
	(generator "pcbnew")
	(generator_version "10.0")
	(general
		(thickness 1.6)
		(legacy_teardrops no)
	)
	(paper "A4")
	(title_block
		(title "Bryce Canyon_F.DPB_16315-1-OCP.brd")
		(comment 1 "Bryce Canyon / footprints 1518-1525 of 2223")
	)
	(layers
		(0 "F.Cu" signal "TOP")
		(4 "In1.Cu" signal "L2GND")
		(6 "In2.Cu" signal "L3")
		(8 "In3.Cu" signal "L4GND")
		(10 "In4.Cu" signal "L5")
		(12 "In5.Cu" signal "L6VCC")
		(14 "In6.Cu" signal "L7VCC")
		(16 "In7.Cu" signal "L8")
		(18 "In8.Cu" signal "L9GND")
		(20 "In9.Cu" signal "L10")
		(22 "In10.Cu" signal "L11GND")
		(2 "B.Cu" signal "BOTTOM")
		(9 "F.Adhes" user "F.Adhesive")
		(11 "B.Adhes" user "B.Adhesive")
		(13 "F.Paste" user "Package Geometry/Pastemask Top")
		(15 "B.Paste" user "Package Geometry/Pastemask Bottom")
		(5 "F.SilkS" user "Ref Des/Silkscreen Top")
		(7 "B.SilkS" user "Ref Des/Silkscreen Bottom")
		(1 "F.Mask" user "Board Geometry/Soldermask Top")
		(3 "B.Mask" user "Board Geometry/Soldermask Bottom")
		(17 "Dwgs.User" user "User.Drawings")
		(19 "Cmts.User" user "User.Comments")
		(21 "Eco1.User" user "User.Eco1")
		(23 "Eco2.User" user "User.Eco2")
		(25 "Edge.Cuts" user "Board Geometry/Outline")
		(27 "Margin" user)
		(31 "F.CrtYd" user "Package Geometry/Place Bound Top")
		(29 "B.CrtYd" user "Package Geometry/Place Bound Bottom")
		(35 "F.Fab" user "Ref Des/Assembly Top")
		(33 "B.Fab" user "Ref Des/Assembly Bottom")
	)
	(footprint ""
		(layer "F.Cu")
		(at 272.542 -334.304894 180)
		(property "Reference" "VIA49"
			(at 0 0 180)
			(layer "F.SilkS")
			(hide yes)
			(effects
				(font
					(size 1.27 1.27)
				)
			)
		)
		(property "Value" "100OHM-8L-1D6MM-L18L16-GP"
			(at -3.7211 -4.5085 180)
			(unlocked yes)
			(layer "F.Fab")
			(hide yes)
			(effects
				(font
					(size 1.016 1.016)
					(thickness 0.1524)
				)
			)
		)
		(property "Device Type" "VIA-PCIE-4P-394076"
			(at -3.7211 -6.0325 180)
			(unlocked yes)
			(layer "F.Fab")
			(hide yes)
			(effects
				(font
					(size 1.016 1.016)
					(thickness 0.1524)
				)
			)
		)
		(duplicate_pad_numbers_are_jumpers no)
		(fp_rect
			(start -1.9685 0.381)
			(end 1.9685 -0.381)
			(stroke
				(width 0)
				(type default)
			)
			(fill no)
			(layer "F.CrtYd")
		)
		(fp_rect
			(start -1.9685 0.381)
			(end 1.9685 -0.381)
			(stroke
				(width 0)
				(type default)
			)
			(fill no)
			(layer "F.Fab")
		)
		(pad "1" thru_hole circle
			(at -1.5875 0 180)
			(size 0.508 0.508)
			(drill 0.254)
			(layers "*.Cu" "*.Mask")
			(remove_unused_layers no)
			(net "GND")
			(clearance 0.127)
			(thermal_gap 0.127)
		)
		(pad "2" thru_hole circle
			(at -0.5715 0 180)
			(size 0.508 0.508)
			(drill 0.254)
			(layers "*.Cu" "*.Mask")
			(remove_unused_layers no)
			(net "PHY_SCC_A_TO_DRV_A_14_DP")
			(clearance 0.127)
			(thermal_gap 0.127)
		)
		(pad "3" thru_hole circle
			(at 0.5715 0 180)
			(size 0.508 0.508)
			(drill 0.254)
			(layers "*.Cu" "*.Mask")
			(remove_unused_layers no)
			(net "PHY_SCC_A_TO_DRV_A_14_DN")
			(clearance 0.127)
			(thermal_gap 0.127)
		)
		(pad "4" thru_hole circle
			(at 1.5875 0 180)
			(size 0.508 0.508)
			(drill 0.254)
			(layers "*.Cu" "*.Mask")
			(remove_unused_layers no)
			(net "GND")
			(clearance 0.127)
			(thermal_gap 0.127)
		)
	)
	(footprint ""
		(layer "F.Cu")
		(at 367.287302 -275.735542 180)
		(property "Reference" "R308"
			(at 0 0 180)
			(layer "F.SilkS")
			(hide yes)
			(effects
				(font
					(size 1.27 1.27)
				)
			)
		)
		(property "Value" "0R2J-2-GP"
			(at 0.064008 -3.993896 180)
			(unlocked yes)
			(layer "F.Fab")
			(hide yes)
			(effects
				(font
					(size 1.016 1.016)
					(thickness 0.1524)
				)
			)
		)
		(property "Device Type" "R402H16"
			(at 0.064008 -5.517896 180)
			(unlocked yes)
			(layer "F.Fab")
			(hide yes)
			(effects
				(font
					(size 1.016 1.016)
					(thickness 0.1524)
				)
			)
		)
		(duplicate_pad_numbers_are_jumpers no)
		(fp_line
			(start 0.508 -0.9398)
			(end -0.508 -0.9398)
			(stroke
				(width 0.1524)
				(type default)
			)
			(layer "F.SilkS")
		)
		(fp_line
			(start -0.508 -0.9398)
			(end -0.508 0.9398)
			(stroke
				(width 0.1524)
				(type default)
			)
			(layer "F.SilkS")
		)
		(fp_rect
			(start -0.508 0.9398)
			(end 0.508 -0.9398)
			(stroke
				(width 0)
				(type default)
			)
			(fill no)
			(layer "F.CrtYd")
		)
		(fp_rect
			(start -0.508 0.9398)
			(end 0.508 -0.9398)
			(stroke
				(width 0)
				(type default)
			)
			(fill no)
			(layer "F.Fab")
		)
		(pad "1" smd custom
			(at 0 -0.4445 180)
			(size 0.1397 0.1397)
			(layers "F.Cu" "F.Mask" "F.Paste")
			(net "SW_HDD_G7")
			(options
				(clearance outline)
				(anchor circle)
			)
			(primitives
				(gr_poly
					(pts
						(arc
							(start -0.1778 -0.2794)
							(mid -0.249642 -0.249642)
							(end -0.2794 -0.1778)
						)
						(arc
							(start -0.2794 0.1778)
							(mid -0.249642 0.249642)
							(end -0.1778 0.2794)
						)
						(arc
							(start 0.1778 0.2794)
							(mid 0.249642 0.249642)
							(end 0.2794 0.1778)
						)
						(arc
							(start 0.2794 -0.1778)
							(mid 0.249642 -0.249642)
							(end 0.1778 -0.2794)
						)
					)
					(width 0)
					(fill yes)
				)
			)
		)
		(pad "2" smd custom
			(at 0 0.4445 180)
			(size 0.1397 0.1397)
			(layers "F.Cu" "F.Mask" "F.Paste")
			(net "SW_HDD_R7")
			(options
				(clearance outline)
				(anchor circle)
			)
			(primitives
				(gr_poly
					(pts
						(arc
							(start -0.1778 -0.2794)
							(mid -0.249642 -0.249642)
							(end -0.2794 -0.1778)
						)
						(arc
							(start -0.2794 0.1778)
							(mid -0.249642 0.249642)
							(end -0.1778 0.2794)
						)
						(arc
							(start 0.1778 0.2794)
							(mid 0.249642 0.249642)
							(end 0.2794 0.1778)
						)
						(arc
							(start 0.2794 -0.1778)
							(mid 0.249642 -0.249642)
							(end 0.1778 -0.2794)
						)
					)
					(width 0)
					(fill yes)
				)
			)
		)
	)
	(footprint ""
		(layer "F.Cu")
		(at 274.283932 -392.79068 -90)
		(property "Reference" "D40"
			(at 0 0 270)
			(layer "F.SilkS")
			(hide yes)
			(effects
				(font
					(size 1.27 1.27)
				)
			)
		)
		(property "Value" "SMCJ14A-13-F-GP"
			(at -4.445 1.1684 270)
			(unlocked yes)
			(layer "F.Fab")
			(hide yes)
			(effects
				(font
					(size 1.016 1.016)
					(thickness 0.1524)
				)
			)
		)
		(property "Device Type" "D795930AKH104"
			(at -4.445 -0.3556 270)
			(unlocked yes)
			(layer "F.Fab")
			(hide yes)
			(effects
				(font
					(size 1.016 1.016)
					(thickness 0.1524)
				)
			)
		)
		(duplicate_pad_numbers_are_jumpers no)
		(fp_line
			(start 3.2004 5.0419)
			(end -3.2004 5.0419)
			(stroke
				(width 0.508)
				(type default)
			)
			(layer "F.SilkS")
		)
		(fp_line
			(start -3.2004 4.8641)
			(end 3.2004 4.8641)
			(stroke
				(width 0.1524)
				(type default)
			)
			(layer "F.SilkS")
		)
		(fp_line
			(start 3.2004 4.8641)
			(end 3.2004 -4.8641)
			(stroke
				(width 0.1524)
				(type default)
			)
			(layer "F.SilkS")
		)
		(fp_line
			(start -3.2004 -4.8641)
			(end -3.2004 4.8641)
			(stroke
				(width 0.1524)
				(type default)
			)
			(layer "F.SilkS")
		)
		(fp_line
			(start 3.2004 -4.8641)
			(end -3.2004 -4.8641)
			(stroke
				(width 0.1524)
				(type default)
			)
			(layer "F.SilkS")
		)
		(fp_poly
			(pts
				(xy -2.9464 3.429) (xy -1.4859 3.429) (xy -1.4859 3.9751) (xy 1.4859 3.9751) (xy 1.4859 3.429) (xy 2.9464 3.429)
				(xy 2.9464 -3.429) (xy 1.4859 -3.429) (xy 1.4859 -3.9751) (xy -1.4859 -3.9751) (xy -1.4859 -3.429)
				(xy -2.9464 -3.429)
			)
			(stroke
				(width 0)
				(type default)
			)
			(fill no)
			(layer "F.CrtYd")
		)
		(fp_poly
			(pts
				(xy -3.4544 4.9403) (xy -3.4544 -4.9403) (xy 3.4544 -4.9403) (xy 3.4544 -3.429) (xy 1.4859 -3.429)
				(xy 1.4859 -3.9751) (xy -1.4859 -3.9751) (xy -1.4859 -3.429) (xy -2.9464 -3.429) (xy -2.9464 3.429)
				(xy -1.4859 3.429) (xy -1.4859 3.9751) (xy 1.4859 3.9751) (xy 1.4859 3.429) (xy 2.9464 3.429) (xy 2.9464 -3.4163)
				(xy 3.4544 -3.4163) (xy 3.4544 4.9403)
			)
			(stroke
				(width 0)
				(type default)
			)
			(fill no)
			(layer "F.CrtYd")
		)
		(fp_rect
			(start -3.4544 4.9403)
			(end 3.4544 -4.9403)
			(stroke
				(width 0)
				(type default)
			)
			(fill no)
			(layer "F.Fab")
		)
		(pad "A" smd rect
			(at 0 -3.592068 270)
			(size 3.2258 2.032)
			(layers "F.Cu" "F.Mask" "F.Paste")
			(net "GND")
		)
		(pad "K" smd rect
			(at 0 3.592068 270)
			(size 3.2258 2.032)
			(layers "F.Cu" "F.Mask" "F.Paste")
			(net "P12V_IN")
		)
	)
	(footprint ""
		(layer "F.Cu")
		(at 242.896644 -382.70815)
		(property "Reference" "R1177"
			(at 0 0 0)
			(layer "F.SilkS")
			(hide yes)
			(effects
				(font
					(size 1.27 1.27)
				)
			)
		)
		(property "Value" "0R5J-5-GP"
			(at 0 -8.9535 0)
			(unlocked yes)
			(layer "F.Fab")
			(hide yes)
			(effects
				(font
					(size 1.27 1.016)
					(thickness 0.1524)
				)
			)
		)
		(property "Device Type" "R805H24"
			(at 0 -10.6299 0)
			(unlocked yes)
			(layer "F.Fab")
			(hide yes)
			(effects
				(font
					(size 1.27 1.016)
					(thickness 0.1524)
				)
			)
		)
		(duplicate_pad_numbers_are_jumpers no)
		(fp_line
			(start -0.889 -1.7018)
			(end -0.889 0.2794)
			(stroke
				(width 0.1524)
				(type default)
			)
			(layer "F.SilkS")
		)
		(fp_line
			(start -0.889 0.0762)
			(end -0.889 1.7018)
			(stroke
				(width 0.1524)
				(type default)
			)
			(layer "F.SilkS")
		)
		(fp_line
			(start -0.889 1.7018)
			(end 0.889 1.7018)
			(stroke
				(width 0.1524)
				(type default)
			)
			(layer "F.SilkS")
		)
		(fp_line
			(start 0.889 -1.7018)
			(end -0.889 -1.7018)
			(stroke
				(width 0.1524)
				(type default)
			)
			(layer "F.SilkS")
		)
		(fp_line
			(start 0.889 -1.7018)
			(end 0.889 -0.381)
			(stroke
				(width 0.1524)
				(type default)
			)
			(layer "F.SilkS")
		)
		(fp_line
			(start 0.889 1.7018)
			(end 0.889 -0.508)
			(stroke
				(width 0.1524)
				(type default)
			)
			(layer "F.SilkS")
		)
		(fp_poly
			(pts
				(xy 0.9652 -1.778) (xy 0.9652 1.778) (xy -0.9652 1.778) (xy -0.9652 -1.778)
			)
			(stroke
				(width 0)
				(type default)
			)
			(fill no)
			(layer "F.CrtYd")
		)
		(fp_rect
			(start -0.9652 1.778)
			(end 0.9652 -1.778)
			(stroke
				(width 0)
				(type default)
			)
			(fill no)
			(layer "F.Fab")
		)
		(pad "1" smd rect
			(at 0 -0.9652)
			(size 1.397 1.143)
			(layers "F.Cu" "F.Mask" "F.Paste")
			(net "MB3_CM_GATE")
		)
		(pad "2" smd rect
			(at 0 0.9652)
			(size 1.397 1.143)
			(layers "F.Cu" "F.Mask" "F.Paste")
			(net "MB3_CM_GATE_R")
		)
	)
	(footprint ""
		(layer "F.Cu")
		(at 365.052102 -303.954942 180)
		(property "Reference" "C137"
			(at 0 0 180)
			(layer "F.SilkS")
			(hide yes)
			(effects
				(font
					(size 1.27 1.27)
				)
			)
		)
		(property "Value" "SC4D7U25V5KX-1-GP"
			(at -0.0762 -6.1214 180)
			(unlocked yes)
			(layer "F.Fab")
			(hide yes)
			(effects
				(font
					(size 1.016 1.016)
					(thickness 0.1524)
				)
			)
		)
		(property "Device Type" "C805H58"
			(at -0.0762 -8.1534 180)
			(unlocked yes)
			(layer "F.Fab")
			(hide yes)
			(effects
				(font
					(size 1.016 1.016)
					(thickness 0.1524)
				)
			)
		)
		(duplicate_pad_numbers_are_jumpers no)
		(fp_line
			(start 0.635 0)
			(end -0.635 0)
			(stroke
				(width 0.508)
				(type default)
			)
			(layer "F.SilkS")
		)
		(fp_rect
			(start -0.9652 1.778)
			(end 0.9652 -1.778)
			(stroke
				(width 0)
				(type default)
			)
			(fill no)
			(layer "F.CrtYd")
		)
		(fp_poly
			(pts
				(xy -0.9652 -1.778) (xy 0.9652 -1.778) (xy 0.9652 1.778) (xy -0.9652 1.778)
			)
			(stroke
				(width 0)
				(type default)
			)
			(fill no)
			(layer "F.Fab")
		)
		(pad "1" smd rect
			(at 0 -0.9652 180)
			(size 1.397 1.143)
			(layers "F.Cu" "F.Mask" "F.Paste")
			(net "P12V_HDD7")
		)
		(pad "2" smd rect
			(at 0 0.9652 180)
			(size 1.397 1.143)
			(layers "F.Cu" "F.Mask" "F.Paste")
			(net "GND")
		)
	)
	(footprint ""
		(layer "F.Cu")
		(at 255.700276 -248.87936 180)
		(property "Reference" "R62"
			(at 0 0 180)
			(layer "F.SilkS")
			(hide yes)
			(effects
				(font
					(size 1.27 1.27)
				)
			)
		)
		(property "Value" "4K7R2F-GP"
			(at 0.064008 -3.993896 180)
			(unlocked yes)
			(layer "F.Fab")
			(hide yes)
			(effects
				(font
					(size 1.016 1.016)
					(thickness 0.1524)
				)
			)
		)
		(property "Device Type" "R402H16"
			(at 0.064008 -5.517896 180)
			(unlocked yes)
			(layer "F.Fab")
			(hide yes)
			(effects
				(font
					(size 1.016 1.016)
					(thickness 0.1524)
				)
			)
		)
		(duplicate_pad_numbers_are_jumpers no)
		(fp_line
			(start 0.508 -0.9398)
			(end -0.508 -0.9398)
			(stroke
				(width 0.1524)
				(type default)
			)
			(layer "F.SilkS")
		)
		(fp_line
			(start -0.508 -0.9398)
			(end -0.508 0.9398)
			(stroke
				(width 0.1524)
				(type default)
			)
			(layer "F.SilkS")
		)
		(fp_rect
			(start -0.508 0.9398)
			(end 0.508 -0.9398)
			(stroke
				(width 0)
				(type default)
			)
			(fill no)
			(layer "F.CrtYd")
		)
		(fp_rect
			(start -0.508 0.9398)
			(end 0.508 -0.9398)
			(stroke
				(width 0)
				(type default)
			)
			(fill no)
			(layer "F.Fab")
		)
		(pad "1" smd custom
			(at 0 -0.4445 180)
			(size 0.1397 0.1397)
			(layers "F.Cu" "F.Mask" "F.Paste")
			(net "P3V3_STBY_A")
			(options
				(clearance outline)
				(anchor circle)
			)
			(primitives
				(gr_poly
					(pts
						(arc
							(start -0.1778 -0.2794)
							(mid -0.249642 -0.249642)
							(end -0.2794 -0.1778)
						)
						(arc
							(start -0.2794 0.1778)
							(mid -0.249642 0.249642)
							(end -0.1778 0.2794)
						)
						(arc
							(start 0.1778 0.2794)
							(mid 0.249642 0.249642)
							(end 0.2794 0.1778)
						)
						(arc
							(start 0.2794 -0.1778)
							(mid 0.249642 -0.249642)
							(end 0.1778 -0.2794)
						)
					)
					(width 0)
					(fill yes)
				)
			)
		)
		(pad "2" smd custom
			(at 0 0.4445 180)
			(size 0.1397 0.1397)
			(layers "F.Cu" "F.Mask" "F.Paste")
			(net "IO_EXP6_A2")
			(options
				(clearance outline)
				(anchor circle)
			)
			(primitives
				(gr_poly
					(pts
						(arc
							(start -0.1778 -0.2794)
							(mid -0.249642 -0.249642)
							(end -0.2794 -0.1778)
						)
						(arc
							(start -0.2794 0.1778)
							(mid -0.249642 0.249642)
							(end -0.1778 0.2794)
						)
						(arc
							(start 0.1778 0.2794)
							(mid 0.249642 0.249642)
							(end 0.2794 0.1778)
						)
						(arc
							(start 0.2794 -0.1778)
							(mid 0.249642 -0.249642)
							(end 0.1778 -0.2794)
						)
					)
					(width 0)
					(fill yes)
				)
			)
		)
	)
	(footprint ""
		(layer "F.Cu")
		(at 99.278948 -180.064918 90)
		(property "Reference" "R456"
			(at 0 0 90)
			(layer "F.SilkS")
			(hide yes)
			(effects
				(font
					(size 1.27 1.27)
				)
			)
		)
		(property "Value" "220R3F-1-GP"
			(at -0.0254 -2.5146 90)
			(unlocked yes)
			(layer "F.Fab")
			(hide yes)
			(effects
				(font
					(size 1.016 1.016)
					(thickness 0.1524)
				)
			)
		)
		(property "Device Type" "R603H22"
			(at -0.0254 -4.0386 90)
			(unlocked yes)
			(layer "F.Fab")
			(hide yes)
			(effects
				(font
					(size 1.016 1.016)
					(thickness 0.1524)
				)
			)
		)
		(duplicate_pad_numbers_are_jumpers no)
		(fp_line
			(start 0.2032 0)
			(end 0.4826 0)
			(stroke
				(width 0.2032)
				(type default)
			)
			(layer "F.SilkS")
		)
		(fp_line
			(start -0.4826 0)
			(end -0.2032 0)
			(stroke
				(width 0.2032)
				(type default)
			)
			(layer "F.SilkS")
		)
		(fp_rect
			(start -0.5842 1.3335)
			(end 0.5842 -1.3335)
			(stroke
				(width 0)
				(type default)
			)
			(fill no)
			(layer "F.CrtYd")
		)
		(fp_rect
			(start -0.5842 1.3335)
			(end 0.5842 -1.3335)
			(stroke
				(width 0)
				(type default)
			)
			(fill no)
			(layer "F.Fab")
		)
		(pad "1" smd custom
			(at 0 -0.762 90)
			(size 0.2159 0.2159)
			(layers "F.Cu" "F.Mask" "F.Paste")
			(net "HDD_PRSNT_14")
			(options
				(clearance outline)
				(anchor circle)
			)
			(primitives
				(gr_poly
					(pts
						(arc
							(start -0.3302 -0.4318)
							(mid -0.402042 -0.402042)
							(end -0.4318 -0.3302)
						)
						(arc
							(start -0.4318 0.3302)
							(mid -0.402042 0.402042)
							(end -0.3302 0.4318)
						)
						(arc
							(start 0.3302 0.4318)
							(mid 0.402042 0.402042)
							(end 0.4318 0.3302)
						)
						(arc
							(start 0.4318 -0.3302)
							(mid 0.402042 -0.402042)
							(end 0.3302 -0.4318)
						)
					)
					(width 0)
					(fill yes)
				)
			)
		)
		(pad "2" smd custom
			(at 0 0.762 90)
			(size 0.2159 0.2159)
			(layers "F.Cu" "F.Mask" "F.Paste")
			(net "DRIVE_A_14_INS")
			(options
				(clearance outline)
				(anchor circle)
			)
			(primitives
				(gr_poly
					(pts
						(arc
							(start -0.3302 -0.4318)
							(mid -0.402042 -0.402042)
							(end -0.4318 -0.3302)
						)
						(arc
							(start -0.4318 0.3302)
							(mid -0.402042 0.402042)
							(end -0.3302 0.4318)
						)
						(arc
							(start 0.3302 0.4318)
							(mid 0.402042 0.402042)
							(end 0.4318 0.3302)
						)
						(arc
							(start 0.4318 -0.3302)
							(mid 0.402042 -0.402042)
							(end 0.3302 -0.4318)
						)
					)
					(width 0)
					(fill yes)
				)
			)
		)
	)
	(footprint ""
		(layer "F.Cu")
		(at 67.728846 -65.064894 90)
		(property "Reference" "R709"
			(at 0 0 90)
			(layer "F.SilkS")
			(hide yes)
			(effects
				(font
					(size 1.27 1.27)
				)
			)
		)
		(property "Value" "220R3F-1-GP"
			(at -0.0254 -2.5146 90)
			(unlocked yes)
			(layer "F.Fab")
			(hide yes)
			(effects
				(font
					(size 1.016 1.016)
					(thickness 0.1524)
				)
			)
		)
		(property "Device Type" "R603H22"
			(at -0.0254 -4.0386 90)
			(unlocked yes)
			(layer "F.Fab")
			(hide yes)
			(effects
				(font
					(size 1.016 1.016)
					(thickness 0.1524)
				)
			)
		)
		(duplicate_pad_numbers_are_jumpers no)
		(fp_line
			(start 0.2032 0)
			(end 0.4826 0)
			(stroke
				(width 0.2032)
				(type default)
			)
			(layer "F.SilkS")
		)
		(fp_line
			(start -0.4826 0)
			(end -0.2032 0)
			(stroke
				(width 0.2032)
				(type default)
			)
			(layer "F.SilkS")
		)
		(fp_rect
			(start -0.5842 1.3335)
			(end 0.5842 -1.3335)
			(stroke
				(width 0)
				(type default)
			)
			(fill no)
			(layer "F.CrtYd")
		)
		(fp_rect
			(start -0.5842 1.3335)
			(end 0.5842 -1.3335)
			(stroke
				(width 0)
				(type default)
			)
			(fill no)
			(layer "F.Fab")
		)
		(pad "1" smd custom
			(at 0 -0.762 90)
			(size 0.2159 0.2159)
			(layers "F.Cu" "F.Mask" "F.Paste")
			(net "HDD_PRSNT_25")
			(options
				(clearance outline)
				(anchor circle)
			)
			(primitives
				(gr_poly
					(pts
						(arc
							(start -0.3302 -0.4318)
							(mid -0.402042 -0.402042)
							(end -0.4318 -0.3302)
						)
						(arc
							(start -0.4318 0.3302)
							(mid -0.402042 0.402042)
							(end -0.3302 0.4318)
						)
						(arc
							(start 0.3302 0.4318)
							(mid 0.402042 0.402042)
							(end 0.4318 0.3302)
						)
						(arc
							(start 0.4318 -0.3302)
							(mid 0.402042 -0.402042)
							(end 0.3302 -0.4318)
						)
					)
					(width 0)
					(fill yes)
				)
			)
		)
		(pad "2" smd custom
			(at 0 0.762 90)
			(size 0.2159 0.2159)
			(layers "F.Cu" "F.Mask" "F.Paste")
			(net "DRIVE_A_25_INS")
			(options
				(clearance outline)
				(anchor circle)
			)
			(primitives
				(gr_poly
					(pts
						(arc
							(start -0.3302 -0.4318)
							(mid -0.402042 -0.402042)
							(end -0.4318 -0.3302)
						)
						(arc
							(start -0.4318 0.3302)
							(mid -0.402042 0.402042)
							(end -0.3302 0.4318)
						)
						(arc
							(start 0.3302 0.4318)
							(mid 0.402042 0.402042)
							(end 0.4318 0.3302)
						)
						(arc
							(start 0.4318 -0.3302)
							(mid 0.402042 -0.402042)
							(end 0.3302 -0.4318)
						)
					)
					(width 0)
					(fill yes)
				)
			)
		)
	)
)
